FILE_TYPE = CONNECTIVITY;
{Allegro Design Entry HDL 17.2-2016 S081 (4005846) 1/11/2022}
"PAGE_NUMBER" = 48;
0"NC";
1"NC_CPU1_HBM0_VIEWDIG1";
2"NC_CPU1_HBM1_VIEWDIG0";
3"NC_CPU1_HBM1_VIEWDIG1";
4"NC_CPU1_HBM2_VIEWDIG0";
5"NC_CPU1_HBM2_VIEWDIG1";
6"NC_CPU1_MDFI_DIE11_NS0";
7"NC_CPU1_MDFI_DIE11_EW0";
8"NC_CPU1_MDFI_DIE11_NS1";
9"NC_CPU1_VIEWPIN_GNR2";
10"NC_CPU1_VIEWPIN_GNR0";
11"NC_CPU1_VIEWPIN_GNR1";
12"NC_CPU1_VIEWPIN_GNR3";
13"NC_CPU1_HBM0_VIEWDIG0";
14"NC_CPU1_MDFI_DIE01_EW0";
15"NC_CPU1_SOC_SPARE0";
16"NC_CPU1_SOC_SPARE4";
17"NC_CPU1_MDFI_DIE01_NS1";
18"TP_CPU1_DIE_HVM_EN_LVC1";
19"NC_CPU1_MDFI_DIE01_NS0";
20"NC_CPU1_HBM3_VIEWDIG0";
21"NC_CPU1_MDFI_DIE00_NS1";
22"NC_CPU1_MDFI_DIE00_NS0";
23"NC_CPU1_HBM3_VIEWDIG1";
24"NC_CPU1_SOC_SPARE1";
25"NC_CPU1_MDFI_DIE00_EW0";
26"NC_CPU1_SOC_SPARE5";
27"NC_CPU1_MDFI_DIE00_EW1";
28"NC_CPU1_MDFI_DIE01_EW1";
29"NC_CPU1_MDFI_DIE10_NS1";
30"NC_CPU1_MDFI_DIE10_EW0";
31"NC_CPU1_MDFI_DIE10_EW1";
32"NC_CPU1_MDFI_DIE10_NS0";
33"NC_CPU1_MDFI_DIE11_EW1";
%"SOCKET4677_AZIF0045P001C01CS"
"5","(550,3125)","0","pure_quanta","I1";
;
PART_NUMBER"DGA^7000023"
PART_TYPE"SMLF"
MATERIAL"IO"
VALUE"SOCKET4677_AZIF0045-P001C01CS"
$LOCATION"U1"
CDS_LIB"pure_quanta"
NEEDS_NO_SIZE"TRUE"
CDS_LMAN_SYM_OUTLINE"-1050,1050,1050,-1000"
CDS_LOCATION"U1"
$SEC"5"
CDS_SEC"5";
"RSVD99"
$PN"CH69"33;
"RSVD92"
$PN"CF22"32;
"RSVD85"
$PN"CD30"31;
"RSVD84"
$PN"CD26"30;
"RSVD83"
$PN"CD22"29;
"RSVD82"
$PN"CC66"28;
"RSVD71"
$PN"BR21"27;
"RSVD68"
$PN"BP65"26;
"RSVD67"
$PN"BP22"25;
"RSVD65"
$PN"BM65"24;
"RSVD63"
$PN"BL60"23;
"RSVD60"
$PN"BK22"22;
"RSVD57"
$PN"BJ21"21;
"RSVD54"
$PN"BG78"20;
"RSVD51"
$PN"BF71"19;
"RSVD45"
$PN"BE21"18;
"RSVD43"
$PN"BD71"17;
"RSVD31"
$PN"BA25"16;
"RSVD26"
$PN"AY24"15;
"RSVD21"
$PN"AV65"14;
"RSVD165"
$PN"W17"2;
"RSVD164"
$PN"U17"13;
"RSVD160"
$PN"EG17"1;
"RSVD154"
$PN"CY57"12;
"RSVD149"
$PN"CW58"11;
"RSVD147"
$PN"CW41"3;
"RSVD138"
$PN"CT26"10;
"RSVD133"
$PN"CR25"9;
"RSVD112"
$PN"CK67"8;
"RSVD107"
$PN"CJ70"7;
"RSVD106"
$PN"CJ68"6;
"RSVD1"
$PN"AD77"5;
"RSVD0"
$PN"AC78"4;
END.
